(kicad_pcb
	(version 20260206)
	(generator "pcbnew")
	(generator_version "10.0")
	(general
		(thickness 1.6)
		(legacy_teardrops no)
	)
	(paper "A4")
	(title_block
		(title "01162023_DA0F0TEBIF0_F0T_Expander_BD_F_brd_V02_OCP.brd")
		(comment 1 "Grand Teton / footprint 6602 of 9728 (PEX1), pads 1308-1423 of 2397")
	)
	(layers
		(0 "F.Cu" signal "TOP")
		(4 "In1.Cu" signal "GND")
		(6 "In2.Cu" signal "VCC")
		(8 "In3.Cu" signal "VCC1")
		(10 "In4.Cu" signal "GND1")
		(12 "In5.Cu" signal "IN1")
		(14 "In6.Cu" signal "GND2")
		(16 "In7.Cu" signal "IN2")
		(18 "In8.Cu" signal "GND3")
		(20 "In9.Cu" signal "IN3")
		(22 "In10.Cu" signal "GND4")
		(24 "In11.Cu" signal "IN4")
		(26 "In12.Cu" signal "GND5")
		(28 "In13.Cu" signal "IN5")
		(30 "In14.Cu" signal "GND6")
		(32 "In15.Cu" signal "IN6")
		(34 "In16.Cu" signal "GND7")
		(2 "B.Cu" signal "BOTTOM")
		(9 "F.Adhes" user "F.Adhesive")
		(11 "B.Adhes" user "B.Adhesive")
		(13 "F.Paste" user "Package Geometry/Pastemask Top")
		(15 "B.Paste" user "Package Geometry/Pastemask Bottom")
		(5 "F.SilkS" user "Ref Des/Silkscreen Top")
		(7 "B.SilkS" user "Ref Des/Silkscreen Bottom")
		(1 "F.Mask" user "Board Geometry/Soldermask Top")
		(3 "B.Mask" user "Board Geometry/Soldermask Bottom")
		(17 "Dwgs.User" user "User.Drawings")
		(19 "Cmts.User" user "User.Comments")
		(21 "Eco1.User" user "User.Eco1")
		(23 "Eco2.User" user "User.Eco2")
		(25 "Edge.Cuts" user "Board Geometry/Outline")
		(27 "Margin" user)
		(31 "F.CrtYd" user "Package Geometry/Place Bound Top")
		(29 "B.CrtYd" user "Package Geometry/Place Bound Bottom")
		(35 "F.Fab" user "Ref Des/Assembly Top")
		(33 "B.Fab" user "Ref Des/Assembly Bottom")
	)
	(footprint ""
		(layer "F.Cu")
		(at 175.749966 -295.89984)
		(property "Reference" "PEX1"
			(at -3.353562 35.593274 0)
			(unlocked yes)
			(layer "F.SilkS")
			(effects
				(font
					(size 2.032 1.524)
					(thickness 0.1524)
				)
				(justify left)
			)
		)
		(property "Value" ""
			(at 0 0 0)
			(layer "F.Fab")
			(effects
				(font
					(size 1.27 1.27)
				)
			)
		)
		(duplicate_pad_numbers_are_jumpers no)
		(pad "BE36" smd circle
			(at 10.450068 18.999962)
			(size 0.4572 0.4572)
			(layers "F.Cu" "F.Mask" "F.Paste")
			(net "GND")
		)
		(pad "BE37" smd circle
			(at 11.400028 18.999962)
			(size 0.4572 0.4572)
			(layers "F.Cu" "F.Mask" "F.Paste")
			(net "GND")
		)
		(pad "BE38" smd circle
			(at 12.349988 18.999962)
			(size 0.4572 0.4572)
			(layers "F.Cu" "F.Mask" "F.Paste")
			(net "GND")
		)
		(pad "BE39" smd circle
			(at 13.299948 18.999962)
			(size 0.4572 0.4572)
			(layers "F.Cu" "F.Mask" "F.Paste")
			(net "GND")
		)
		(pad "BE40" smd circle
			(at 14.249908 18.999962)
			(size 0.4572 0.4572)
			(layers "F.Cu" "F.Mask" "F.Paste")
			(net "GND")
		)
		(pad "BE41" smd circle
			(at 15.200122 18.999962)
			(size 0.4572 0.4572)
			(layers "F.Cu" "F.Mask" "F.Paste")
			(net "GND")
		)
		(pad "BE42" smd circle
			(at 16.150082 18.999962)
			(size 0.4572 0.4572)
			(layers "F.Cu" "F.Mask" "F.Paste")
			(net "GND")
		)
		(pad "BE43" smd circle
			(at 17.100042 18.999962)
			(size 0.4572 0.4572)
			(layers "F.Cu" "F.Mask" "F.Paste")
			(net "GND")
		)
		(pad "BE44" smd circle
			(at 18.050002 18.999962)
			(size 0.4572 0.4572)
			(layers "F.Cu" "F.Mask" "F.Paste")
			(net "GND")
		)
		(pad "BE45" smd circle
			(at 18.999962 18.999962)
			(size 0.4572 0.4572)
			(layers "F.Cu" "F.Mask" "F.Paste")
			(net "GND")
		)
		(pad "BE46" smd circle
			(at 19.949922 18.999962)
			(size 0.4572 0.4572)
			(layers "F.Cu" "F.Mask" "F.Paste")
			(net "GND")
		)
		(pad "BE47" smd circle
			(at 20.899882 18.999962)
			(size 0.4572 0.4572)
			(layers "F.Cu" "F.Mask" "F.Paste")
			(net "GND")
		)
		(pad "BE48" smd circle
			(at 21.850096 18.999962)
			(size 0.4572 0.4572)
			(layers "F.Cu" "F.Mask" "F.Paste")
			(net "P5E_PEX1_STN0_TX_DP<8>")
		)
		(pad "BE49" smd circle
			(at 22.800056 18.999962)
			(size 0.4572 0.4572)
			(layers "F.Cu" "F.Mask" "F.Paste")
			(net "P5E_PEX1_STN0_TX_DN<8>")
		)
		(pad "BF1" smd circle
			(at -22.800056 19.949922)
			(size 0.4572 0.4572)
			(layers "F.Cu" "F.Mask" "F.Paste")
			(net "GND")
		)
		(pad "BF2" smd circle
			(at -21.850096 19.949922)
			(size 0.4572 0.4572)
			(layers "F.Cu" "F.Mask" "F.Paste")
			(net "GND")
		)
		(pad "BF3" smd circle
			(at -20.899882 19.949922)
			(size 0.4572 0.4572)
			(layers "F.Cu" "F.Mask" "F.Paste")
			(net "GND")
		)
		(pad "BF4" smd circle
			(at -19.949922 19.949922)
			(size 0.4572 0.4572)
			(layers "F.Cu" "F.Mask" "F.Paste")
			(net "Net_1707")
		)
		(pad "BF5" smd circle
			(at -18.999962 19.949922)
			(size 0.4572 0.4572)
			(layers "F.Cu" "F.Mask" "F.Paste")
			(net "GND")
		)
		(pad "BF6" smd circle
			(at -18.050002 19.949922)
			(size 0.4572 0.4572)
			(layers "F.Cu" "F.Mask" "F.Paste")
			(net "Net_1725")
		)
		(pad "BF7" smd circle
			(at -17.100042 19.949922)
			(size 0.4572 0.4572)
			(layers "F.Cu" "F.Mask" "F.Paste")
			(net "GND")
		)
		(pad "BF8" smd circle
			(at -16.150082 19.949922)
			(size 0.4572 0.4572)
			(layers "F.Cu" "F.Mask" "F.Paste")
			(net "Net_1713")
		)
		(pad "BF9" smd circle
			(at -15.200122 19.949922)
			(size 0.4572 0.4572)
			(layers "F.Cu" "F.Mask" "F.Paste")
			(net "GND")
		)
		(pad "BF10" smd circle
			(at -14.249908 19.949922)
			(size 0.4572 0.4572)
			(layers "F.Cu" "F.Mask" "F.Paste")
			(net "P5E_PEX1_STN2_RX_DP<46>")
		)
		(pad "BF11" smd circle
			(at -13.299948 19.949922)
			(size 0.4572 0.4572)
			(layers "F.Cu" "F.Mask" "F.Paste")
			(net "GND")
		)
		(pad "BF12" smd circle
			(at -12.349988 19.949922)
			(size 0.4572 0.4572)
			(layers "F.Cu" "F.Mask" "F.Paste")
			(net "P5E_PEX1_STN2_RX_DP<44>")
		)
		(pad "BF13" smd circle
			(at -11.400028 19.949922)
			(size 0.4572 0.4572)
			(layers "F.Cu" "F.Mask" "F.Paste")
			(net "GND")
		)
		(pad "BF14" smd circle
			(at -10.450068 19.949922)
			(size 0.4572 0.4572)
			(layers "F.Cu" "F.Mask" "F.Paste")
			(net "P5E_PEX1_STN2_RX_DP<42>")
		)
		(pad "BF15" smd circle
			(at -9.500108 19.949922)
			(size 0.4572 0.4572)
			(layers "F.Cu" "F.Mask" "F.Paste")
			(net "GND")
		)
		(pad "BF16" smd circle
			(at -8.549894 19.949922)
			(size 0.4572 0.4572)
			(layers "F.Cu" "F.Mask" "F.Paste")
			(net "P5E_PEX1_STN2_RX_DP<40>")
		)
		(pad "BF17" smd circle
			(at -7.599934 19.949922)
			(size 0.4572 0.4572)
			(layers "F.Cu" "F.Mask" "F.Paste")
			(net "GND")
		)
		(pad "BF18" smd circle
			(at -6.649974 19.949922)
			(size 0.4572 0.4572)
			(layers "F.Cu" "F.Mask" "F.Paste")
			(net "P5E_PEX1_STN2_RX_DP<38>")
		)
		(pad "BF19" smd circle
			(at -5.700014 19.949922)
			(size 0.4572 0.4572)
			(layers "F.Cu" "F.Mask" "F.Paste")
			(net "GND")
		)
		(pad "BF20" smd circle
			(at -4.750054 19.949922)
			(size 0.4572 0.4572)
			(layers "F.Cu" "F.Mask" "F.Paste")
			(net "P5E_PEX1_STN2_RX_DP<36>")
		)
		(pad "BF21" smd circle
			(at -3.800094 19.949922)
			(size 0.4572 0.4572)
			(layers "F.Cu" "F.Mask" "F.Paste")
			(net "GND")
		)
		(pad "BF22" smd circle
			(at -2.84988 19.949922)
			(size 0.4572 0.4572)
			(layers "F.Cu" "F.Mask" "F.Paste")
			(net "P5E_PEX1_STN2_RX_DP<34>")
		)
		(pad "BF23" smd circle
			(at -1.89992 19.949922)
			(size 0.4572 0.4572)
			(layers "F.Cu" "F.Mask" "F.Paste")
			(net "GND")
		)
		(pad "BF24" smd circle
			(at -0.94996 19.949922)
			(size 0.4572 0.4572)
			(layers "F.Cu" "F.Mask" "F.Paste")
			(net "P5E_PEX1_STN2_RX_DP<32>")
		)
		(pad "BF25" smd circle
			(at 0 19.949922)
			(size 0.4572 0.4572)
			(layers "F.Cu" "F.Mask" "F.Paste")
			(net "GND")
		)
		(pad "BF26" smd circle
			(at 0.94996 19.949922)
			(size 0.4572 0.4572)
			(layers "F.Cu" "F.Mask" "F.Paste")
			(net "P5E_PEX1_STN1_RX_DP<17>")
		)
		(pad "BF27" smd circle
			(at 1.89992 19.949922)
			(size 0.4572 0.4572)
			(layers "F.Cu" "F.Mask" "F.Paste")
			(net "GND")
		)
		(pad "BF28" smd circle
			(at 2.84988 19.949922)
			(size 0.4572 0.4572)
			(layers "F.Cu" "F.Mask" "F.Paste")
			(net "P5E_PEX1_STN1_RX_DP<19>")
		)
		(pad "BF29" smd circle
			(at 3.800094 19.949922)
			(size 0.4572 0.4572)
			(layers "F.Cu" "F.Mask" "F.Paste")
			(net "GND")
		)
		(pad "BF30" smd circle
			(at 4.750054 19.949922)
			(size 0.4572 0.4572)
			(layers "F.Cu" "F.Mask" "F.Paste")
			(net "P5E_PEX1_STN1_RX_DP<21>")
		)
		(pad "BF31" smd circle
			(at 5.700014 19.949922)
			(size 0.4572 0.4572)
			(layers "F.Cu" "F.Mask" "F.Paste")
			(net "GND")
		)
		(pad "BF32" smd circle
			(at 6.649974 19.949922)
			(size 0.4572 0.4572)
			(layers "F.Cu" "F.Mask" "F.Paste")
			(net "P5E_PEX1_STN1_RX_DP<23>")
		)
		(pad "BF33" smd circle
			(at 7.599934 19.949922)
			(size 0.4572 0.4572)
			(layers "F.Cu" "F.Mask" "F.Paste")
			(net "GND")
		)
		(pad "BF34" smd circle
			(at 8.549894 19.949922)
			(size 0.4572 0.4572)
			(layers "F.Cu" "F.Mask" "F.Paste")
			(net "P5E_PEX1_STN1_RX_DP<25>")
		)
		(pad "BF35" smd circle
			(at 9.500108 19.949922)
			(size 0.4572 0.4572)
			(layers "F.Cu" "F.Mask" "F.Paste")
			(net "GND")
		)
		(pad "BF36" smd circle
			(at 10.450068 19.949922)
			(size 0.4572 0.4572)
			(layers "F.Cu" "F.Mask" "F.Paste")
			(net "P5E_PEX1_STN1_RX_DP<27>")
		)
		(pad "BF37" smd circle
			(at 11.400028 19.949922)
			(size 0.4572 0.4572)
			(layers "F.Cu" "F.Mask" "F.Paste")
			(net "GND")
		)
		(pad "BF38" smd circle
			(at 12.349988 19.949922)
			(size 0.4572 0.4572)
			(layers "F.Cu" "F.Mask" "F.Paste")
			(net "P5E_PEX1_STN1_RX_DP<29>")
		)
		(pad "BF39" smd circle
			(at 13.299948 19.949922)
			(size 0.4572 0.4572)
			(layers "F.Cu" "F.Mask" "F.Paste")
			(net "GND")
		)
		(pad "BF40" smd circle
			(at 14.249908 19.949922)
			(size 0.4572 0.4572)
			(layers "F.Cu" "F.Mask" "F.Paste")
			(net "P5E_PEX1_STN1_RX_DP<31>")
		)
		(pad "BF41" smd circle
			(at 15.200122 19.949922)
			(size 0.4572 0.4572)
			(layers "F.Cu" "F.Mask" "F.Paste")
			(net "GND")
		)
		(pad "BF42" smd circle
			(at 16.150082 19.949922)
			(size 0.4572 0.4572)
			(layers "F.Cu" "F.Mask" "F.Paste")
			(net "P5E_PEX1_STN0_RX_DP<14>")
		)
		(pad "BF43" smd circle
			(at 17.100042 19.949922)
			(size 0.4572 0.4572)
			(layers "F.Cu" "F.Mask" "F.Paste")
			(net "GND")
		)
		(pad "BF44" smd circle
			(at 18.050002 19.949922)
			(size 0.4572 0.4572)
			(layers "F.Cu" "F.Mask" "F.Paste")
			(net "P5E_PEX1_STN0_RX_DP<12>")
		)
		(pad "BF45" smd circle
			(at 18.999962 19.949922)
			(size 0.4572 0.4572)
			(layers "F.Cu" "F.Mask" "F.Paste")
			(net "GND")
		)
		(pad "BF46" smd circle
			(at 19.949922 19.949922)
			(size 0.4572 0.4572)
			(layers "F.Cu" "F.Mask" "F.Paste")
			(net "P5E_PEX1_STN0_RX_DP<10>")
		)
		(pad "BF47" smd circle
			(at 20.899882 19.949922)
			(size 0.4572 0.4572)
			(layers "F.Cu" "F.Mask" "F.Paste")
			(net "GND")
		)
		(pad "BF48" smd circle
			(at 21.850096 19.949922)
			(size 0.4572 0.4572)
			(layers "F.Cu" "F.Mask" "F.Paste")
			(net "GND")
		)
		(pad "BF49" smd circle
			(at 22.800056 19.949922)
			(size 0.4572 0.4572)
			(layers "F.Cu" "F.Mask" "F.Paste")
			(net "GND")
		)
		(pad "BG1" smd circle
			(at -22.800056 20.899882)
			(size 0.4572 0.4572)
			(layers "F.Cu" "F.Mask" "F.Paste")
			(net "Net_1727")
		)
		(pad "BG2" smd circle
			(at -21.850096 20.899882)
			(size 0.4572 0.4572)
			(layers "F.Cu" "F.Mask" "F.Paste")
			(net "Net_1715")
		)
		(pad "BG3" smd circle
			(at -20.899882 20.899882)
			(size 0.4572 0.4572)
			(layers "F.Cu" "F.Mask" "F.Paste")
			(net "GND")
		)
		(pad "BG4" smd circle
			(at -19.949922 20.899882)
			(size 0.4572 0.4572)
			(layers "F.Cu" "F.Mask" "F.Paste")
			(net "Net_1708")
		)
		(pad "BG5" smd circle
			(at -18.999962 20.899882)
			(size 0.4572 0.4572)
			(layers "F.Cu" "F.Mask" "F.Paste")
			(net "GND")
		)
		(pad "BG6" smd circle
			(at -18.050002 20.899882)
			(size 0.4572 0.4572)
			(layers "F.Cu" "F.Mask" "F.Paste")
			(net "Net_1721")
		)
		(pad "BG7" smd circle
			(at -17.100042 20.899882)
			(size 0.4572 0.4572)
			(layers "F.Cu" "F.Mask" "F.Paste")
			(net "GND")
		)
		(pad "BG8" smd circle
			(at -16.150082 20.899882)
			(size 0.4572 0.4572)
			(layers "F.Cu" "F.Mask" "F.Paste")
			(net "Net_1400")
		)
		(pad "BG9" smd circle
			(at -15.200122 20.899882)
			(size 0.4572 0.4572)
			(layers "F.Cu" "F.Mask" "F.Paste")
			(net "GND")
		)
		(pad "BG10" smd circle
			(at -14.249908 20.899882)
			(size 0.4572 0.4572)
			(layers "F.Cu" "F.Mask" "F.Paste")
			(net "P5E_PEX1_STN2_RX_DN<46>")
		)
		(pad "BG11" smd circle
			(at -13.299948 20.899882)
			(size 0.4572 0.4572)
			(layers "F.Cu" "F.Mask" "F.Paste")
			(net "GND")
		)
		(pad "BG12" smd circle
			(at -12.349988 20.899882)
			(size 0.4572 0.4572)
			(layers "F.Cu" "F.Mask" "F.Paste")
			(net "P5E_PEX1_STN2_RX_DN<44>")
		)
		(pad "BG13" smd circle
			(at -11.400028 20.899882)
			(size 0.4572 0.4572)
			(layers "F.Cu" "F.Mask" "F.Paste")
			(net "GND")
		)
		(pad "BG14" smd circle
			(at -10.450068 20.899882)
			(size 0.4572 0.4572)
			(layers "F.Cu" "F.Mask" "F.Paste")
			(net "P5E_PEX1_STN2_RX_DN<42>")
		)
		(pad "BG15" smd circle
			(at -9.500108 20.899882)
			(size 0.4572 0.4572)
			(layers "F.Cu" "F.Mask" "F.Paste")
			(net "GND")
		)
		(pad "BG16" smd circle
			(at -8.549894 20.899882)
			(size 0.4572 0.4572)
			(layers "F.Cu" "F.Mask" "F.Paste")
			(net "P5E_PEX1_STN2_RX_DN<40>")
		)
		(pad "BG17" smd circle
			(at -7.599934 20.899882)
			(size 0.4572 0.4572)
			(layers "F.Cu" "F.Mask" "F.Paste")
			(net "GND")
		)
		(pad "BG18" smd circle
			(at -6.649974 20.899882)
			(size 0.4572 0.4572)
			(layers "F.Cu" "F.Mask" "F.Paste")
			(net "P5E_PEX1_STN2_RX_DN<38>")
		)
		(pad "BG19" smd circle
			(at -5.700014 20.899882)
			(size 0.4572 0.4572)
			(layers "F.Cu" "F.Mask" "F.Paste")
			(net "GND")
		)
		(pad "BG20" smd circle
			(at -4.750054 20.899882)
			(size 0.4572 0.4572)
			(layers "F.Cu" "F.Mask" "F.Paste")
			(net "P5E_PEX1_STN2_RX_DN<36>")
		)
		(pad "BG21" smd circle
			(at -3.800094 20.899882)
			(size 0.4572 0.4572)
			(layers "F.Cu" "F.Mask" "F.Paste")
			(net "GND")
		)
		(pad "BG22" smd circle
			(at -2.84988 20.899882)
			(size 0.4572 0.4572)
			(layers "F.Cu" "F.Mask" "F.Paste")
			(net "P5E_PEX1_STN2_RX_DN<34>")
		)
		(pad "BG23" smd circle
			(at -1.89992 20.899882)
			(size 0.4572 0.4572)
			(layers "F.Cu" "F.Mask" "F.Paste")
			(net "GND")
		)
		(pad "BG24" smd circle
			(at -0.94996 20.899882)
			(size 0.4572 0.4572)
			(layers "F.Cu" "F.Mask" "F.Paste")
			(net "P5E_PEX1_STN2_RX_DN<32>")
		)
		(pad "BG25" smd circle
			(at 0 20.899882)
			(size 0.4572 0.4572)
			(layers "F.Cu" "F.Mask" "F.Paste")
			(net "GND")
		)
		(pad "BG26" smd circle
			(at 0.94996 20.899882)
			(size 0.4572 0.4572)
			(layers "F.Cu" "F.Mask" "F.Paste")
			(net "P5E_PEX1_STN1_RX_DN<17>")
		)
		(pad "BG27" smd circle
			(at 1.89992 20.899882)
			(size 0.4572 0.4572)
			(layers "F.Cu" "F.Mask" "F.Paste")
			(net "GND")
		)
		(pad "BG28" smd circle
			(at 2.84988 20.899882)
			(size 0.4572 0.4572)
			(layers "F.Cu" "F.Mask" "F.Paste")
			(net "P5E_PEX1_STN1_RX_DN<19>")
		)
		(pad "BG29" smd circle
			(at 3.800094 20.899882)
			(size 0.4572 0.4572)
			(layers "F.Cu" "F.Mask" "F.Paste")
			(net "GND")
		)
		(pad "BG30" smd circle
			(at 4.750054 20.899882)
			(size 0.4572 0.4572)
			(layers "F.Cu" "F.Mask" "F.Paste")
			(net "P5E_PEX1_STN1_RX_DN<21>")
		)
		(pad "BG31" smd circle
			(at 5.700014 20.899882)
			(size 0.4572 0.4572)
			(layers "F.Cu" "F.Mask" "F.Paste")
			(net "GND")
		)
		(pad "BG32" smd circle
			(at 6.649974 20.899882)
			(size 0.4572 0.4572)
			(layers "F.Cu" "F.Mask" "F.Paste")
			(net "P5E_PEX1_STN1_RX_DN<23>")
		)
		(pad "BG33" smd circle
			(at 7.599934 20.899882)
			(size 0.4572 0.4572)
			(layers "F.Cu" "F.Mask" "F.Paste")
			(net "GND")
		)
		(pad "BG34" smd circle
			(at 8.549894 20.899882)
			(size 0.4572 0.4572)
			(layers "F.Cu" "F.Mask" "F.Paste")
			(net "P5E_PEX1_STN1_RX_DN<25>")
		)
		(pad "BG35" smd circle
			(at 9.500108 20.899882)
			(size 0.4572 0.4572)
			(layers "F.Cu" "F.Mask" "F.Paste")
			(net "GND")
		)
		(pad "BG36" smd circle
			(at 10.450068 20.899882)
			(size 0.4572 0.4572)
			(layers "F.Cu" "F.Mask" "F.Paste")
			(net "P5E_PEX1_STN1_RX_DN<27>")
		)
		(pad "BG37" smd circle
			(at 11.400028 20.899882)
			(size 0.4572 0.4572)
			(layers "F.Cu" "F.Mask" "F.Paste")
			(net "GND")
		)
		(pad "BG38" smd circle
			(at 12.349988 20.899882)
			(size 0.4572 0.4572)
			(layers "F.Cu" "F.Mask" "F.Paste")
			(net "P5E_PEX1_STN1_RX_DN<29>")
		)
		(pad "BG39" smd circle
			(at 13.299948 20.899882)
			(size 0.4572 0.4572)
			(layers "F.Cu" "F.Mask" "F.Paste")
			(net "GND")
		)
		(pad "BG40" smd circle
			(at 14.249908 20.899882)
			(size 0.4572 0.4572)
			(layers "F.Cu" "F.Mask" "F.Paste")
			(net "P5E_PEX1_STN1_RX_DN<31>")
		)
		(pad "BG41" smd circle
			(at 15.200122 20.899882)
			(size 0.4572 0.4572)
			(layers "F.Cu" "F.Mask" "F.Paste")
			(net "GND")
		)
		(pad "BG42" smd circle
			(at 16.150082 20.899882)
			(size 0.4572 0.4572)
			(layers "F.Cu" "F.Mask" "F.Paste")
			(net "P5E_PEX1_STN0_RX_DN<14>")
		)
		(pad "BG43" smd circle
			(at 17.100042 20.899882)
			(size 0.4572 0.4572)
			(layers "F.Cu" "F.Mask" "F.Paste")
			(net "GND")
		)
		(pad "BG44" smd circle
			(at 18.050002 20.899882)
			(size 0.4572 0.4572)
			(layers "F.Cu" "F.Mask" "F.Paste")
			(net "P5E_PEX1_STN0_RX_DN<12>")
		)
		(pad "BG45" smd circle
			(at 18.999962 20.899882)
			(size 0.4572 0.4572)
			(layers "F.Cu" "F.Mask" "F.Paste")
			(net "GND")
		)
		(pad "BG46" smd circle
			(at 19.949922 20.899882)
			(size 0.4572 0.4572)
			(layers "F.Cu" "F.Mask" "F.Paste")
			(net "P5E_PEX1_STN0_RX_DN<10>")
		)
		(pad "BG47" smd circle
			(at 20.899882 20.899882)
			(size 0.4572 0.4572)
			(layers "F.Cu" "F.Mask" "F.Paste")
			(net "GND")
		)
		(pad "BG48" smd circle
			(at 21.850096 20.899882)
			(size 0.4572 0.4572)
			(layers "F.Cu" "F.Mask" "F.Paste")
			(net "P5E_PEX1_STN0_RX_DP<8>")
		)
		(pad "BG49" smd circle
			(at 22.800056 20.899882)
			(size 0.4572 0.4572)
			(layers "F.Cu" "F.Mask" "F.Paste")
			(net "P5E_PEX1_STN0_RX_DN<8>")
		)
		(pad "BH1" smd circle
			(at -22.800056 21.850096)
			(size 0.4572 0.4572)
			(layers "F.Cu" "F.Mask" "F.Paste")
			(net "GND")
		)
		(pad "BH2" smd circle
			(at -21.850096 21.850096)
			(size 0.4572 0.4572)
			(layers "F.Cu" "F.Mask" "F.Paste")
			(net "GND")
		)
		(pad "BH3" smd circle
			(at -20.899882 21.850096)
			(size 0.4572 0.4572)
			(layers "F.Cu" "F.Mask" "F.Paste")
			(net "Net_1730")
		)
		(pad "BH4" smd circle
			(at -19.949922 21.850096)
			(size 0.4572 0.4572)
			(layers "F.Cu" "F.Mask" "F.Paste")
			(net "GND")
		)
	)
)
